(kicad_pcb
	(version 20260206)
	(generator "pcbnew")
	(generator_version "10.0")
	(general
		(thickness 1.6)
		(legacy_teardrops no)
	)
	(paper "A4")
	(title_block
		(title "Bryce Canyon_IOM_IOC_16318-2_OCP.brd")
		(comment 1 "Bryce Canyon / footprints 1356-1363 of 1605")
	)
	(layers
		(0 "F.Cu" signal "TOP")
		(4 "In1.Cu" signal "L2GND")
		(6 "In2.Cu" signal "L3")
		(8 "In3.Cu" signal "L4VCC")
		(10 "In4.Cu" signal "L5VCC")
		(12 "In5.Cu" signal "L6")
		(14 "In6.Cu" signal "L7GND")
		(2 "B.Cu" signal "BOTTOM")
		(9 "F.Adhes" user "F.Adhesive")
		(11 "B.Adhes" user "B.Adhesive")
		(13 "F.Paste" user "Package Geometry/Pastemask Top")
		(15 "B.Paste" user "Package Geometry/Pastemask Bottom")
		(5 "F.SilkS" user "Ref Des/Silkscreen Top")
		(7 "B.SilkS" user "Ref Des/Silkscreen Bottom")
		(1 "F.Mask" user "Board Geometry/Soldermask Top")
		(3 "B.Mask" user "Board Geometry/Soldermask Bottom")
		(17 "Dwgs.User" user "User.Drawings")
		(19 "Cmts.User" user "User.Comments")
		(21 "Eco1.User" user "User.Eco1")
		(23 "Eco2.User" user "User.Eco2")
		(25 "Edge.Cuts" user "Board Geometry/Outline")
		(27 "Margin" user)
		(31 "F.CrtYd" user "Package Geometry/Place Bound Top")
		(29 "B.CrtYd" user "Package Geometry/Place Bound Bottom")
		(35 "F.Fab" user "Ref Des/Assembly Top")
		(33 "B.Fab" user "Ref Des/Assembly Bottom")
	)
	(footprint ""
		(layer "B.Cu")
		(at 191.68999 -23.241 -90)
		(property "Reference" "C493"
			(at 0 0 90)
			(layer "B.SilkS")
			(hide yes)
			(effects
				(font
					(size 1.27 1.27)
				)
				(justify mirror)
			)
		)
		(property "Value" "SCD01U16V1KX-GP"
			(at 2.8321 -1.7399 270)
			(unlocked yes)
			(layer "B.Fab")
			(hide yes)
			(effects
				(font
					(size 1.016 1.016)
					(thickness 0.1524)
				)
				(justify mirror)
			)
		)
		(property "Device Type" "C0201H13"
			(at 2.8321 -3.2639 270)
			(unlocked yes)
			(layer "B.Fab")
			(hide yes)
			(effects
				(font
					(size 1.016 1.016)
					(thickness 0.1524)
				)
				(justify mirror)
			)
		)
		(duplicate_pad_numbers_are_jumpers no)
		(fp_rect
			(start 0.2794 0.6477)
			(end -0.2794 -0.6477)
			(stroke
				(width 0)
				(type default)
			)
			(fill no)
			(layer "B.CrtYd")
		)
		(fp_rect
			(start 0.2794 0.6477)
			(end -0.2794 -0.6477)
			(stroke
				(width 0)
				(type default)
			)
			(fill no)
			(layer "B.Fab")
		)
		(pad "1" smd custom
			(at 0 -0.2794 90)
			(size 0.0762 0.0762)
			(layers "B.Cu" "B.Mask" "B.Paste")
			(net "PHY_CON_A_TO_IOC_2_DN")
			(options
				(clearance outline)
				(anchor circle)
			)
			(primitives
				(gr_poly
					(pts
						(arc
							(start 0.1524 0.127)
							(mid 0.137521 0.162921)
							(end 0.1016 0.1778)
						)
						(arc
							(start -0.1016 0.1778)
							(mid -0.137521 0.162921)
							(end -0.1524 0.127)
						)
						(arc
							(start -0.1524 -0.127)
							(mid -0.137521 -0.162921)
							(end -0.1016 -0.1778)
						)
						(arc
							(start 0.1016 -0.1778)
							(mid 0.137521 -0.162921)
							(end 0.1524 -0.127)
						)
					)
					(width 0)
					(fill yes)
				)
			)
		)
		(pad "2" smd custom
			(at 0 0.2794 90)
			(size 0.0762 0.0762)
			(layers "B.Cu" "B.Mask" "B.Paste")
			(net "PHY_CON_A_TO_IOC_2_DN_C")
			(options
				(clearance outline)
				(anchor circle)
			)
			(primitives
				(gr_poly
					(pts
						(arc
							(start 0.1524 0.127)
							(mid 0.137521 0.162921)
							(end 0.1016 0.1778)
						)
						(arc
							(start -0.1016 0.1778)
							(mid -0.137521 0.162921)
							(end -0.1524 0.127)
						)
						(arc
							(start -0.1524 -0.127)
							(mid -0.137521 -0.162921)
							(end -0.1016 -0.1778)
						)
						(arc
							(start 0.1016 -0.1778)
							(mid 0.137521 -0.162921)
							(end 0.1524 -0.127)
						)
					)
					(width 0)
					(fill yes)
				)
			)
		)
	)
	(footprint ""
		(layer "B.Cu")
		(at 184.4929 -81.50352)
		(property "Reference" "C392"
			(at 0 0 0)
			(layer "B.SilkS")
			(hide yes)
			(effects
				(font
					(size 1.27 1.27)
				)
				(justify mirror)
			)
		)
		(property "Value" "SC1U16V2KX-7-GP"
			(at -1.7526 -1.6002 0)
			(unlocked yes)
			(layer "B.Fab")
			(hide yes)
			(effects
				(font
					(size 1.016 1.016)
					(thickness 0.1524)
				)
				(justify mirror)
			)
		)
		(property "Device Type" "C402-TO0D2H24"
			(at -1.7526 -3.1242 0)
			(unlocked yes)
			(layer "B.Fab")
			(hide yes)
			(effects
				(font
					(size 1.016 1.016)
					(thickness 0.1524)
				)
				(justify mirror)
			)
		)
		(duplicate_pad_numbers_are_jumpers no)
		(fp_rect
			(start 0.4826 0.889)
			(end -0.4826 -0.889)
			(stroke
				(width 0)
				(type default)
			)
			(fill no)
			(layer "B.CrtYd")
		)
		(fp_rect
			(start 0.4826 0.889)
			(end -0.4826 -0.889)
			(stroke
				(width 0)
				(type default)
			)
			(fill no)
			(layer "B.Fab")
		)
		(pad "1" smd custom
			(at 0 -0.4572 180)
			(size 0.1524 0.1524)
			(layers "B.Cu" "B.Mask" "B.Paste")
			(net "P0V975")
			(options
				(clearance outline)
				(anchor circle)
			)
			(primitives
				(gr_poly
					(pts
						(arc
							(start -0.254 -0.3048)
							(mid -0.325842 -0.275042)
							(end -0.3556 -0.2032)
						)
						(arc
							(start -0.3556 0.2032)
							(mid -0.325842 0.275042)
							(end -0.254 0.3048)
						)
						(arc
							(start 0.254 0.3048)
							(mid 0.325842 0.275042)
							(end 0.3556 0.2032)
						)
						(arc
							(start 0.3556 -0.2032)
							(mid 0.325842 -0.275042)
							(end 0.254 -0.3048)
						)
					)
					(width 0)
					(fill yes)
				)
			)
		)
		(pad "2" smd custom
			(at 0 0.4572 180)
			(size 0.1524 0.1524)
			(layers "B.Cu" "B.Mask" "B.Paste")
			(net "GND")
			(options
				(clearance outline)
				(anchor circle)
			)
			(primitives
				(gr_poly
					(pts
						(arc
							(start -0.254 -0.3048)
							(mid -0.325842 -0.275042)
							(end -0.3556 -0.2032)
						)
						(arc
							(start -0.3556 0.2032)
							(mid -0.325842 0.275042)
							(end -0.254 0.3048)
						)
						(arc
							(start 0.254 0.3048)
							(mid 0.325842 0.275042)
							(end 0.3556 0.2032)
						)
						(arc
							(start 0.3556 -0.2032)
							(mid 0.325842 -0.275042)
							(end 0.254 -0.3048)
						)
					)
					(width 0)
					(fill yes)
				)
			)
		)
	)
	(footprint ""
		(layer "B.Cu")
		(at 61.0362 -145.034 90)
		(property "Reference" "R165"
			(at 0 0 90)
			(layer "B.SilkS")
			(hide yes)
			(effects
				(font
					(size 1.27 1.27)
				)
				(justify mirror)
			)
		)
		(property "Value" "0R2J-2-GP"
			(at -0.064008 -3.993896 90)
			(unlocked yes)
			(layer "B.Fab")
			(hide yes)
			(effects
				(font
					(size 1.016 1.016)
					(thickness 0.1524)
				)
				(justify mirror)
			)
		)
		(property "Device Type" "R402H16"
			(at -0.064008 -5.517896 90)
			(unlocked yes)
			(layer "B.Fab")
			(hide yes)
			(effects
				(font
					(size 1.016 1.016)
					(thickness 0.1524)
				)
				(justify mirror)
			)
		)
		(duplicate_pad_numbers_are_jumpers no)
		(fp_line
			(start 0.508 -0.9398)
			(end 0.508 0.9398)
			(stroke
				(width 0.1524)
				(type default)
			)
			(layer "B.SilkS")
		)
		(fp_line
			(start -0.508 -0.9398)
			(end 0.508 -0.9398)
			(stroke
				(width 0.1524)
				(type default)
			)
			(layer "B.SilkS")
		)
		(fp_rect
			(start 0.508 0.9398)
			(end -0.508 -0.9398)
			(stroke
				(width 0)
				(type default)
			)
			(fill no)
			(layer "B.CrtYd")
		)
		(fp_rect
			(start 0.508 0.9398)
			(end -0.508 -0.9398)
			(stroke
				(width 0)
				(type default)
			)
			(fill no)
			(layer "B.Fab")
		)
		(pad "1" smd custom
			(at 0 -0.4445 270)
			(size 0.1397 0.1397)
			(layers "B.Cu" "B.Mask" "B.Paste")
			(net "BMC_SMB13_DAT")
			(options
				(clearance outline)
				(anchor circle)
			)
			(primitives
				(gr_poly
					(pts
						(arc
							(start -0.1778 0.2794)
							(mid -0.249642 0.249642)
							(end -0.2794 0.1778)
						)
						(arc
							(start -0.2794 -0.1778)
							(mid -0.249642 -0.249642)
							(end -0.1778 -0.2794)
						)
						(arc
							(start 0.1778 -0.2794)
							(mid 0.249642 -0.249642)
							(end 0.2794 -0.1778)
						)
						(arc
							(start 0.2794 0.1778)
							(mid 0.249642 0.249642)
							(end 0.1778 0.2794)
						)
					)
					(width 0)
					(fill yes)
				)
			)
		)
		(pad "2" smd custom
			(at 0 0.4445 270)
			(size 0.1397 0.1397)
			(layers "B.Cu" "B.Mask" "B.Paste")
			(net "I2C_MEZZ_FRU_SENSOR_SDA")
			(options
				(clearance outline)
				(anchor circle)
			)
			(primitives
				(gr_poly
					(pts
						(arc
							(start -0.1778 0.2794)
							(mid -0.249642 0.249642)
							(end -0.2794 0.1778)
						)
						(arc
							(start -0.2794 -0.1778)
							(mid -0.249642 -0.249642)
							(end -0.1778 -0.2794)
						)
						(arc
							(start 0.1778 -0.2794)
							(mid 0.249642 -0.249642)
							(end 0.2794 -0.1778)
						)
						(arc
							(start 0.2794 0.1778)
							(mid 0.249642 0.249642)
							(end 0.1778 0.2794)
						)
					)
					(width 0)
					(fill yes)
				)
			)
		)
	)
	(footprint ""
		(layer "B.Cu")
		(at 199.7964 -113.538 180)
		(property "Reference" "C260"
			(at 0 0 0)
			(layer "B.SilkS")
			(hide yes)
			(effects
				(font
					(size 1.27 1.27)
				)
				(justify mirror)
			)
		)
		(property "Value" "SC22U6D3V6KX-2-GP"
			(at 0.0762 -5.1308 180)
			(unlocked yes)
			(layer "B.Fab")
			(hide yes)
			(effects
				(font
					(size 1.016 1.016)
					(thickness 0.1524)
				)
				(justify mirror)
			)
		)
		(property "Device Type" "C1206H71"
			(at 0.127 -6.6548 180)
			(unlocked yes)
			(layer "B.Fab")
			(hide yes)
			(effects
				(font
					(size 1.016 1.016)
					(thickness 0.1524)
				)
				(justify mirror)
			)
		)
		(duplicate_pad_numbers_are_jumpers no)
		(fp_line
			(start 1.016 2.2352)
			(end 1.016 0.8382)
			(stroke
				(width 0.1524)
				(type default)
			)
			(layer "B.SilkS")
		)
		(fp_line
			(start 1.016 -0.8382)
			(end 1.016 -2.2352)
			(stroke
				(width 0.1524)
				(type default)
			)
			(layer "B.SilkS")
		)
		(fp_line
			(start 1.016 -2.2352)
			(end -1.016 -2.2352)
			(stroke
				(width 0.1524)
				(type default)
			)
			(layer "B.SilkS")
		)
		(fp_line
			(start -1.016 2.2352)
			(end 1.016 2.2352)
			(stroke
				(width 0.1524)
				(type default)
			)
			(layer "B.SilkS")
		)
		(fp_line
			(start -1.016 0.8382)
			(end -1.016 2.2352)
			(stroke
				(width 0.1524)
				(type default)
			)
			(layer "B.SilkS")
		)
		(fp_line
			(start -1.016 -2.2352)
			(end -1.016 -0.8382)
			(stroke
				(width 0.1524)
				(type default)
			)
			(layer "B.SilkS")
		)
		(fp_rect
			(start 1.0922 2.3114)
			(end -1.0922 -2.3114)
			(stroke
				(width 0)
				(type default)
			)
			(fill no)
			(layer "B.CrtYd")
		)
		(fp_poly
			(pts
				(xy -1.0922 -2.3114) (xy -1.0922 2.3114) (xy 1.0922 2.3114) (xy 1.0922 -2.3114)
			)
			(stroke
				(width 0)
				(type default)
			)
			(fill no)
			(layer "B.Fab")
		)
		(pad "1" smd rect
			(at 0 -1.397)
			(size 1.651 1.27)
			(layers "B.Cu" "B.Mask" "B.Paste")
			(net "P0V975")
		)
		(pad "2" smd rect
			(at 0 1.397)
			(size 1.651 1.27)
			(layers "B.Cu" "B.Mask" "B.Paste")
			(net "GND")
		)
	)
	(footprint ""
		(layer "B.Cu")
		(at 93.37548 -152.746456 180)
		(property "Reference" "C9"
			(at 0 0 0)
			(layer "B.SilkS")
			(hide yes)
			(effects
				(font
					(size 1.27 1.27)
				)
				(justify mirror)
			)
		)
		(property "Value" "SC1U16V2KX-7-GP"
			(at -1.7526 -1.6002 180)
			(unlocked yes)
			(layer "B.Fab")
			(hide yes)
			(effects
				(font
					(size 1.016 1.016)
					(thickness 0.1524)
				)
				(justify mirror)
			)
		)
		(property "Device Type" "C402-TO0D2H24"
			(at -1.7526 -3.1242 180)
			(unlocked yes)
			(layer "B.Fab")
			(hide yes)
			(effects
				(font
					(size 1.016 1.016)
					(thickness 0.1524)
				)
				(justify mirror)
			)
		)
		(duplicate_pad_numbers_are_jumpers no)
		(fp_rect
			(start 0.4826 0.889)
			(end -0.4826 -0.889)
			(stroke
				(width 0)
				(type default)
			)
			(fill no)
			(layer "B.CrtYd")
		)
		(fp_rect
			(start 0.4826 0.889)
			(end -0.4826 -0.889)
			(stroke
				(width 0)
				(type default)
			)
			(fill no)
			(layer "B.Fab")
		)
		(pad "1" smd custom
			(at 0 -0.4572)
			(size 0.1524 0.1524)
			(layers "B.Cu" "B.Mask" "B.Paste")
			(net "P3V3_STBY")
			(options
				(clearance outline)
				(anchor circle)
			)
			(primitives
				(gr_poly
					(pts
						(arc
							(start -0.254 -0.3048)
							(mid -0.325842 -0.275042)
							(end -0.3556 -0.2032)
						)
						(arc
							(start -0.3556 0.2032)
							(mid -0.325842 0.275042)
							(end -0.254 0.3048)
						)
						(arc
							(start 0.254 0.3048)
							(mid 0.325842 0.275042)
							(end 0.3556 0.2032)
						)
						(arc
							(start 0.3556 -0.2032)
							(mid 0.325842 -0.275042)
							(end 0.254 -0.3048)
						)
					)
					(width 0)
					(fill yes)
				)
			)
		)
		(pad "2" smd custom
			(at 0 0.4572)
			(size 0.1524 0.1524)
			(layers "B.Cu" "B.Mask" "B.Paste")
			(net "GND")
			(options
				(clearance outline)
				(anchor circle)
			)
			(primitives
				(gr_poly
					(pts
						(arc
							(start -0.254 -0.3048)
							(mid -0.325842 -0.275042)
							(end -0.3556 -0.2032)
						)
						(arc
							(start -0.3556 0.2032)
							(mid -0.325842 0.275042)
							(end -0.254 0.3048)
						)
						(arc
							(start 0.254 0.3048)
							(mid 0.325842 0.275042)
							(end 0.3556 0.2032)
						)
						(arc
							(start 0.3556 -0.2032)
							(mid 0.325842 -0.275042)
							(end 0.254 -0.3048)
						)
					)
					(width 0)
					(fill yes)
				)
			)
		)
	)
	(footprint ""
		(layer "B.Cu")
		(at 184.1754 -118.0338 90)
		(property "Reference" "C273"
			(at 0 0 90)
			(layer "B.SilkS")
			(hide yes)
			(effects
				(font
					(size 1.27 1.27)
				)
				(justify mirror)
			)
		)
		(property "Value" "SC10U16V5KX-7-GP-U"
			(at 0.0762 -6.1214 90)
			(unlocked yes)
			(layer "B.Fab")
			(hide yes)
			(effects
				(font
					(size 1.016 1.016)
					(thickness 0.1524)
				)
				(justify mirror)
			)
		)
		(property "Device Type" "C805H58"
			(at 0.0762 -8.1534 90)
			(unlocked yes)
			(layer "B.Fab")
			(hide yes)
			(effects
				(font
					(size 1.016 1.016)
					(thickness 0.1524)
				)
				(justify mirror)
			)
		)
		(duplicate_pad_numbers_are_jumpers no)
		(fp_line
			(start -0.635 0)
			(end 0.635 0)
			(stroke
				(width 0.508)
				(type default)
			)
			(layer "B.SilkS")
		)
		(fp_rect
			(start 0.9652 1.778)
			(end -0.9652 -1.778)
			(stroke
				(width 0)
				(type default)
			)
			(fill no)
			(layer "B.CrtYd")
		)
		(fp_poly
			(pts
				(xy 0.9652 -1.778) (xy -0.9652 -1.778) (xy -0.9652 1.778) (xy 0.9652 1.778)
			)
			(stroke
				(width 0)
				(type default)
			)
			(fill no)
			(layer "B.Fab")
		)
		(pad "1" smd rect
			(at 0 -0.9652 270)
			(size 1.397 1.143)
			(layers "B.Cu" "B.Mask" "B.Paste")
			(net "VT235_VDDH")
		)
		(pad "2" smd rect
			(at 0 0.9652 270)
			(size 1.397 1.143)
			(layers "B.Cu" "B.Mask" "B.Paste")
			(net "GND")
		)
	)
	(footprint ""
		(layer "B.Cu")
		(at 62.2554 -134.93496 -90)
		(property "Reference" "R343"
			(at 0 0 90)
			(layer "B.SilkS")
			(hide yes)
			(effects
				(font
					(size 1.27 1.27)
				)
				(justify mirror)
			)
		)
		(property "Value" "0R2J-2-GP"
			(at -0.064008 -3.993896 270)
			(unlocked yes)
			(layer "B.Fab")
			(hide yes)
			(effects
				(font
					(size 1.016 1.016)
					(thickness 0.1524)
				)
				(justify mirror)
			)
		)
		(property "Device Type" "R402H16"
			(at -0.064008 -5.517896 270)
			(unlocked yes)
			(layer "B.Fab")
			(hide yes)
			(effects
				(font
					(size 1.016 1.016)
					(thickness 0.1524)
				)
				(justify mirror)
			)
		)
		(duplicate_pad_numbers_are_jumpers no)
		(fp_line
			(start -0.508 -0.9398)
			(end 0.508 -0.9398)
			(stroke
				(width 0.1524)
				(type default)
			)
			(layer "B.SilkS")
		)
		(fp_line
			(start 0.508 -0.9398)
			(end 0.508 0.9398)
			(stroke
				(width 0.1524)
				(type default)
			)
			(layer "B.SilkS")
		)
		(fp_rect
			(start 0.508 0.9398)
			(end -0.508 -0.9398)
			(stroke
				(width 0)
				(type default)
			)
			(fill no)
			(layer "B.CrtYd")
		)
		(fp_rect
			(start 0.508 0.9398)
			(end -0.508 -0.9398)
			(stroke
				(width 0)
				(type default)
			)
			(fill no)
			(layer "B.Fab")
		)
		(pad "1" smd custom
			(at 0 -0.4445 90)
			(size 0.1397 0.1397)
			(layers "B.Cu" "B.Mask" "B.Paste")
			(net "COMP_SPARE_0")
			(options
				(clearance outline)
				(anchor circle)
			)
			(primitives
				(gr_poly
					(pts
						(arc
							(start -0.1778 0.2794)
							(mid -0.249642 0.249642)
							(end -0.2794 0.1778)
						)
						(arc
							(start -0.2794 -0.1778)
							(mid -0.249642 -0.249642)
							(end -0.1778 -0.2794)
						)
						(arc
							(start 0.1778 -0.2794)
							(mid 0.249642 -0.249642)
							(end 0.2794 -0.1778)
						)
						(arc
							(start 0.2794 0.1778)
							(mid 0.249642 0.249642)
							(end 0.1778 0.2794)
						)
					)
					(width 0)
					(fill yes)
				)
			)
		)
		(pad "2" smd custom
			(at 0 0.4445 90)
			(size 0.1397 0.1397)
			(layers "B.Cu" "B.Mask" "B.Paste")
			(net "COMP_SPARE_0_R")
			(options
				(clearance outline)
				(anchor circle)
			)
			(primitives
				(gr_poly
					(pts
						(arc
							(start -0.1778 0.2794)
							(mid -0.249642 0.249642)
							(end -0.2794 0.1778)
						)
						(arc
							(start -0.2794 -0.1778)
							(mid -0.249642 -0.249642)
							(end -0.1778 -0.2794)
						)
						(arc
							(start 0.1778 -0.2794)
							(mid 0.249642 -0.249642)
							(end 0.2794 -0.1778)
						)
						(arc
							(start 0.2794 0.1778)
							(mid 0.249642 0.249642)
							(end 0.1778 0.2794)
						)
					)
					(width 0)
					(fill yes)
				)
			)
		)
	)
	(footprint ""
		(layer "B.Cu")
		(at 161.036 -48.895 180)
		(property "Reference" "R747"
			(at 0 0 0)
			(layer "B.SilkS")
			(hide yes)
			(effects
				(font
					(size 1.27 1.27)
				)
				(justify mirror)
			)
		)
		(property "Value" "10KR2F-2-GP"
			(at -0.064008 -3.993896 180)
			(unlocked yes)
			(layer "B.Fab")
			(hide yes)
			(effects
				(font
					(size 1.016 1.016)
					(thickness 0.1524)
				)
				(justify mirror)
			)
		)
		(property "Device Type" "R402H16"
			(at -0.064008 -5.517896 180)
			(unlocked yes)
			(layer "B.Fab")
			(hide yes)
			(effects
				(font
					(size 1.016 1.016)
					(thickness 0.1524)
				)
				(justify mirror)
			)
		)
		(duplicate_pad_numbers_are_jumpers no)
		(fp_line
			(start 0.508 -0.9398)
			(end 0.508 0.9398)
			(stroke
				(width 0.1524)
				(type default)
			)
			(layer "B.SilkS")
		)
		(fp_line
			(start -0.508 -0.9398)
			(end 0.508 -0.9398)
			(stroke
				(width 0.1524)
				(type default)
			)
			(layer "B.SilkS")
		)
		(fp_rect
			(start 0.508 0.9398)
			(end -0.508 -0.9398)
			(stroke
				(width 0)
				(type default)
			)
			(fill no)
			(layer "B.CrtYd")
		)
		(fp_rect
			(start 0.508 0.9398)
			(end -0.508 -0.9398)
			(stroke
				(width 0)
				(type default)
			)
			(fill no)
			(layer "B.Fab")
		)
		(pad "1" smd custom
			(at 0 -0.4445)
			(size 0.1397 0.1397)
			(layers "B.Cu" "B.Mask" "B.Paste")
			(net "P1V8")
			(options
				(clearance outline)
				(anchor circle)
			)
			(primitives
				(gr_poly
					(pts
						(arc
							(start -0.1778 0.2794)
							(mid -0.249642 0.249642)
							(end -0.2794 0.1778)
						)
						(arc
							(start -0.2794 -0.1778)
							(mid -0.249642 -0.249642)
							(end -0.1778 -0.2794)
						)
						(arc
							(start 0.1778 -0.2794)
							(mid 0.249642 -0.249642)
							(end 0.2794 -0.1778)
						)
						(arc
							(start 0.2794 0.1778)
							(mid 0.249642 0.249642)
							(end 0.1778 0.2794)
						)
					)
					(width 0)
					(fill yes)
				)
			)
		)
		(pad "2" smd custom
			(at 0 0.4445)
			(size 0.1397 0.1397)
			(layers "B.Cu" "B.Mask" "B.Paste")
			(net "BYTE_N")
			(options
				(clearance outline)
				(anchor circle)
			)
			(primitives
				(gr_poly
					(pts
						(arc
							(start -0.1778 0.2794)
							(mid -0.249642 0.249642)
							(end -0.2794 0.1778)
						)
						(arc
							(start -0.2794 -0.1778)
							(mid -0.249642 -0.249642)
							(end -0.1778 -0.2794)
						)
						(arc
							(start 0.1778 -0.2794)
							(mid 0.249642 -0.249642)
							(end 0.2794 -0.1778)
						)
						(arc
							(start 0.2794 0.1778)
							(mid 0.249642 0.249642)
							(end 0.1778 0.2794)
						)
					)
					(width 0)
					(fill yes)
				)
			)
		)
	)
)
